(kicad_pcb
	(version 20260206)
	(generator "pcbnew")
	(generator_version "10.0")
	(general
		(thickness 1.6)
		(legacy_teardrops no)
	)
	(paper "A4")
	(title_block
		(title "03242023_DA0F0TMBIJ0_F0T_Motherboard_J_brd_V01_OCP.brd")
		(comment 1 "Grand Teton / footprints 4284-4290 of 6105")
	)
	(layers
		(0 "F.Cu" signal "TOP")
		(4 "In1.Cu" signal "GND")
		(6 "In2.Cu" signal "IN1")
		(8 "In3.Cu" signal "GND1")
		(10 "In4.Cu" signal "IN2")
		(12 "In5.Cu" signal "GND2")
		(14 "In6.Cu" signal "IN3")
		(16 "In7.Cu" signal "GND3")
		(18 "In8.Cu" signal "VCC")
		(20 "In9.Cu" signal "VCC1")
		(22 "In10.Cu" signal "GND4")
		(24 "In11.Cu" signal "IN4")
		(26 "In12.Cu" signal "GND5")
		(28 "In13.Cu" signal "IN5")
		(30 "In14.Cu" signal "GND6")
		(32 "In15.Cu" signal "IN6")
		(34 "In16.Cu" signal "GND7")
		(2 "B.Cu" signal "BOTTOM")
		(9 "F.Adhes" user "F.Adhesive")
		(11 "B.Adhes" user "B.Adhesive")
		(13 "F.Paste" user "Package Geometry/Pastemask Top")
		(15 "B.Paste" user "Package Geometry/Pastemask Bottom")
		(5 "F.SilkS" user "Ref Des/Silkscreen Top")
		(7 "B.SilkS" user "Ref Des/Silkscreen Bottom")
		(1 "F.Mask" user "Board Geometry/Soldermask Top")
		(3 "B.Mask" user "Board Geometry/Soldermask Bottom")
		(17 "Dwgs.User" user "User.Drawings")
		(19 "Cmts.User" user "User.Comments")
		(21 "Eco1.User" user "User.Eco1")
		(23 "Eco2.User" user "User.Eco2")
		(25 "Edge.Cuts" user "Board Geometry/Outline")
		(27 "Margin" user)
		(31 "F.CrtYd" user "Package Geometry/Place Bound Top")
		(29 "B.CrtYd" user "Package Geometry/Place Bound Bottom")
		(35 "F.Fab" user "Ref Des/Assembly Top")
		(33 "B.Fab" user "Ref Des/Assembly Bottom")
	)
	(footprint ""
		(layer "B.Cu")
		(at 333.868014 -338.137246 -90)
		(property "Reference" "PR140"
			(at 0 0 90)
			(layer "B.SilkS")
			(hide yes)
			(effects
				(font
					(size 1.27 1.27)
				)
				(justify mirror)
			)
		)
		(property "Value" ""
			(at 0 0 90)
			(layer "B.Fab")
			(effects
				(font
					(size 1.27 1.27)
				)
				(justify mirror)
			)
		)
		(duplicate_pad_numbers_are_jumpers no)
		(fp_line
			(start -0.7874 0.4064)
			(end 0.7874 0.4064)
			(stroke
				(width 0.1524)
				(type default)
			)
			(layer "B.SilkS")
		)
		(fp_line
			(start 0.7874 0.4064)
			(end 0.7874 -0.4064)
			(stroke
				(width 0.1524)
				(type default)
			)
			(layer "B.SilkS")
		)
		(fp_line
			(start -0.7874 -0.4064)
			(end -0.7874 0.4064)
			(stroke
				(width 0.1524)
				(type default)
			)
			(layer "B.SilkS")
		)
		(fp_line
			(start 0.7874 -0.4064)
			(end -0.7874 -0.4064)
			(stroke
				(width 0.1524)
				(type default)
			)
			(layer "B.SilkS")
		)
		(fp_line
			(start -0.67945 0.3048)
			(end -0.120396 0.3048)
			(stroke
				(width 0.1)
				(type default)
			)
			(layer "B.Fab")
		)
		(fp_line
			(start -0.120396 0.3048)
			(end -0.120396 0.2794)
			(stroke
				(width 0.1)
				(type default)
			)
			(layer "B.Fab")
		)
		(fp_line
			(start 0.12065 0.3048)
			(end 0.67945 0.3048)
			(stroke
				(width 0.1)
				(type default)
			)
			(layer "B.Fab")
		)
		(fp_line
			(start 0.67945 0.3048)
			(end 0.67945 -0.305054)
			(stroke
				(width 0.1)
				(type default)
			)
			(layer "B.Fab")
		)
		(fp_line
			(start -0.120396 0.2794)
			(end 0.12065 0.2794)
			(stroke
				(width 0.1)
				(type default)
			)
			(layer "B.Fab")
		)
		(fp_line
			(start 0.12065 0.2794)
			(end 0.12065 0.3048)
			(stroke
				(width 0.1)
				(type default)
			)
			(layer "B.Fab")
		)
		(fp_line
			(start -0.12065 -0.2794)
			(end -0.12065 -0.3048)
			(stroke
				(width 0.1)
				(type default)
			)
			(layer "B.Fab")
		)
		(fp_line
			(start 0.12065 -0.2794)
			(end -0.12065 -0.2794)
			(stroke
				(width 0.1)
				(type default)
			)
			(layer "B.Fab")
		)
		(fp_line
			(start -0.67945 -0.3048)
			(end -0.67945 0.3048)
			(stroke
				(width 0.1)
				(type default)
			)
			(layer "B.Fab")
		)
		(fp_line
			(start -0.12065 -0.3048)
			(end -0.67945 -0.3048)
			(stroke
				(width 0.1)
				(type default)
			)
			(layer "B.Fab")
		)
		(fp_line
			(start 0.12065 -0.305054)
			(end 0.12065 -0.2794)
			(stroke
				(width 0.1)
				(type default)
			)
			(layer "B.Fab")
		)
		(fp_line
			(start 0.67945 -0.305054)
			(end 0.12065 -0.305054)
			(stroke
				(width 0.1)
				(type default)
			)
			(layer "B.Fab")
		)
		(pad "1" smd circle
			(at 0.40005 0 90)
			(size 0 0)
			(layers "B.Cu" "B.Mask" "B.Paste")
			(net "PVCCIN_CPU0_PVCC")
		)
		(pad "2" smd circle
			(at -0.40005 0 90)
			(size 0 0)
			(layers "B.Cu" "B.Mask" "B.Paste")
			(net "PVCCIN_CPU0_VDD6")
		)
	)
	(footprint ""
		(layer "B.Cu")
		(at 355.397308 -244.820186 -90)
		(property "Reference" "C393"
			(at 0 0 90)
			(layer "B.SilkS")
			(hide yes)
			(effects
				(font
					(size 1.27 1.27)
				)
				(justify mirror)
			)
		)
		(property "Value" ""
			(at 0 0 90)
			(layer "B.Fab")
			(effects
				(font
					(size 1.27 1.27)
				)
				(justify mirror)
			)
		)
		(duplicate_pad_numbers_are_jumpers no)
		(fp_line
			(start -1.524 0.762)
			(end 1.524 0.762)
			(stroke
				(width 0.1524)
				(type default)
			)
			(layer "B.SilkS")
		)
		(fp_line
			(start 1.524 0.762)
			(end 1.524 -0.762)
			(stroke
				(width 0.1524)
				(type default)
			)
			(layer "B.SilkS")
		)
		(fp_line
			(start -1.524 -0.762)
			(end -1.524 0.762)
			(stroke
				(width 0.1524)
				(type default)
			)
			(layer "B.SilkS")
		)
		(fp_line
			(start 1.524 -0.762)
			(end -1.524 -0.762)
			(stroke
				(width 0.1524)
				(type default)
			)
			(layer "B.SilkS")
		)
		(fp_line
			(start -1.1049 0.724916)
			(end -1.1049 -0.724916)
			(stroke
				(width 0.1)
				(type default)
			)
			(layer "B.Fab")
		)
		(fp_line
			(start 1.1049 0.724916)
			(end -1.1049 0.724916)
			(stroke
				(width 0.1)
				(type default)
			)
			(layer "B.Fab")
		)
		(fp_line
			(start -1.1049 -0.724916)
			(end 1.1049 -0.724916)
			(stroke
				(width 0.1)
				(type default)
			)
			(layer "B.Fab")
		)
		(fp_line
			(start 1.1049 -0.724916)
			(end 1.1049 0.724916)
			(stroke
				(width 0.1)
				(type default)
			)
			(layer "B.Fab")
		)
		(pad "1" smd rect
			(at 0.889 0 270)
			(size 1.016 1.27)
			(layers "B.Cu" "B.Mask" "B.Paste")
			(net "PVCCIN_CPU0")
		)
		(pad "2" smd rect
			(at -0.889 0 270)
			(size 1.016 1.27)
			(layers "B.Cu" "B.Mask" "B.Paste")
			(net "GND")
		)
	)
	(footprint ""
		(layer "B.Cu")
		(at 369.49888 -36.921948)
		(property "Reference" "R2510"
			(at 0 0 0)
			(layer "B.SilkS")
			(hide yes)
			(effects
				(font
					(size 1.27 1.27)
				)
				(justify mirror)
			)
		)
		(property "Value" ""
			(at 0 0 0)
			(layer "B.Fab")
			(effects
				(font
					(size 1.27 1.27)
				)
				(justify mirror)
			)
		)
		(duplicate_pad_numbers_are_jumpers no)
		(fp_line
			(start -0.7874 -0.4064)
			(end -0.7874 0.4064)
			(stroke
				(width 0.1524)
				(type default)
			)
			(layer "B.SilkS")
		)
		(fp_line
			(start -0.7874 0.4064)
			(end 0.7874 0.4064)
			(stroke
				(width 0.1524)
				(type default)
			)
			(layer "B.SilkS")
		)
		(fp_line
			(start 0.7874 -0.4064)
			(end -0.7874 -0.4064)
			(stroke
				(width 0.1524)
				(type default)
			)
			(layer "B.SilkS")
		)
		(fp_line
			(start 0.7874 0.4064)
			(end 0.7874 -0.4064)
			(stroke
				(width 0.1524)
				(type default)
			)
			(layer "B.SilkS")
		)
		(fp_line
			(start -0.67945 -0.3048)
			(end -0.67945 0.3048)
			(stroke
				(width 0.1)
				(type default)
			)
			(layer "B.Fab")
		)
		(fp_line
			(start -0.67945 0.3048)
			(end -0.120396 0.3048)
			(stroke
				(width 0.1)
				(type default)
			)
			(layer "B.Fab")
		)
		(fp_line
			(start -0.12065 -0.3048)
			(end -0.67945 -0.3048)
			(stroke
				(width 0.1)
				(type default)
			)
			(layer "B.Fab")
		)
		(fp_line
			(start -0.12065 -0.2794)
			(end -0.12065 -0.3048)
			(stroke
				(width 0.1)
				(type default)
			)
			(layer "B.Fab")
		)
		(fp_line
			(start -0.120396 0.2794)
			(end 0.12065 0.2794)
			(stroke
				(width 0.1)
				(type default)
			)
			(layer "B.Fab")
		)
		(fp_line
			(start -0.120396 0.3048)
			(end -0.120396 0.2794)
			(stroke
				(width 0.1)
				(type default)
			)
			(layer "B.Fab")
		)
		(fp_line
			(start 0.12065 -0.305054)
			(end 0.12065 -0.2794)
			(stroke
				(width 0.1)
				(type default)
			)
			(layer "B.Fab")
		)
		(fp_line
			(start 0.12065 -0.2794)
			(end -0.12065 -0.2794)
			(stroke
				(width 0.1)
				(type default)
			)
			(layer "B.Fab")
		)
		(fp_line
			(start 0.12065 0.2794)
			(end 0.12065 0.3048)
			(stroke
				(width 0.1)
				(type default)
			)
			(layer "B.Fab")
		)
		(fp_line
			(start 0.12065 0.3048)
			(end 0.67945 0.3048)
			(stroke
				(width 0.1)
				(type default)
			)
			(layer "B.Fab")
		)
		(fp_line
			(start 0.67945 -0.305054)
			(end 0.12065 -0.305054)
			(stroke
				(width 0.1)
				(type default)
			)
			(layer "B.Fab")
		)
		(fp_line
			(start 0.67945 0.3048)
			(end 0.67945 -0.305054)
			(stroke
				(width 0.1)
				(type default)
			)
			(layer "B.Fab")
		)
		(pad "1" smd circle
			(at 0.40005 0 180)
			(size 0 0)
			(layers "B.Cu" "B.Mask" "B.Paste")
			(net "P3V3_AUX")
		)
		(pad "2" smd circle
			(at -0.40005 0 180)
			(size 0 0)
			(layers "B.Cu" "B.Mask" "B.Paste")
			(net "FM_M2_E1S_E6_PEDET")
		)
	)
	(footprint ""
		(layer "B.Cu")
		(at 85.389466 -339.983572 -90)
		(property "Reference" "PR295"
			(at 0 0 90)
			(layer "B.SilkS")
			(hide yes)
			(effects
				(font
					(size 1.27 1.27)
				)
				(justify mirror)
			)
		)
		(property "Value" ""
			(at 0 0 90)
			(layer "B.Fab")
			(effects
				(font
					(size 1.27 1.27)
				)
				(justify mirror)
			)
		)
		(duplicate_pad_numbers_are_jumpers no)
		(fp_line
			(start -0.7874 0.4064)
			(end 0.7874 0.4064)
			(stroke
				(width 0.1524)
				(type default)
			)
			(layer "B.SilkS")
		)
		(fp_line
			(start 0.7874 0.4064)
			(end 0.7874 -0.4064)
			(stroke
				(width 0.1524)
				(type default)
			)
			(layer "B.SilkS")
		)
		(fp_line
			(start -0.7874 -0.4064)
			(end -0.7874 0.4064)
			(stroke
				(width 0.1524)
				(type default)
			)
			(layer "B.SilkS")
		)
		(fp_line
			(start 0.7874 -0.4064)
			(end -0.7874 -0.4064)
			(stroke
				(width 0.1524)
				(type default)
			)
			(layer "B.SilkS")
		)
		(fp_line
			(start -0.67945 0.3048)
			(end -0.120396 0.3048)
			(stroke
				(width 0.1)
				(type default)
			)
			(layer "B.Fab")
		)
		(fp_line
			(start -0.120396 0.3048)
			(end -0.120396 0.2794)
			(stroke
				(width 0.1)
				(type default)
			)
			(layer "B.Fab")
		)
		(fp_line
			(start 0.12065 0.3048)
			(end 0.67945 0.3048)
			(stroke
				(width 0.1)
				(type default)
			)
			(layer "B.Fab")
		)
		(fp_line
			(start 0.67945 0.3048)
			(end 0.67945 -0.305054)
			(stroke
				(width 0.1)
				(type default)
			)
			(layer "B.Fab")
		)
		(fp_line
			(start -0.120396 0.2794)
			(end 0.12065 0.2794)
			(stroke
				(width 0.1)
				(type default)
			)
			(layer "B.Fab")
		)
		(fp_line
			(start 0.12065 0.2794)
			(end 0.12065 0.3048)
			(stroke
				(width 0.1)
				(type default)
			)
			(layer "B.Fab")
		)
		(fp_line
			(start -0.12065 -0.2794)
			(end -0.12065 -0.3048)
			(stroke
				(width 0.1)
				(type default)
			)
			(layer "B.Fab")
		)
		(fp_line
			(start 0.12065 -0.2794)
			(end -0.12065 -0.2794)
			(stroke
				(width 0.1)
				(type default)
			)
			(layer "B.Fab")
		)
		(fp_line
			(start -0.67945 -0.3048)
			(end -0.67945 0.3048)
			(stroke
				(width 0.1)
				(type default)
			)
			(layer "B.Fab")
		)
		(fp_line
			(start -0.12065 -0.3048)
			(end -0.67945 -0.3048)
			(stroke
				(width 0.1)
				(type default)
			)
			(layer "B.Fab")
		)
		(fp_line
			(start 0.12065 -0.305054)
			(end 0.12065 -0.2794)
			(stroke
				(width 0.1)
				(type default)
			)
			(layer "B.Fab")
		)
		(fp_line
			(start 0.67945 -0.305054)
			(end 0.12065 -0.305054)
			(stroke
				(width 0.1)
				(type default)
			)
			(layer "B.Fab")
		)
		(pad "1" smd circle
			(at 0.40005 0 90)
			(size 0 0)
			(layers "B.Cu" "B.Mask" "B.Paste")
			(net "PVCCIN_CPU1_VOS6")
		)
		(pad "2" smd circle
			(at -0.40005 0 90)
			(size 0 0)
			(layers "B.Cu" "B.Mask" "B.Paste")
			(net "PVCCIN_CPU1")
		)
	)
	(footprint ""
		(layer "B.Cu")
		(at 158.697168 -319.363344)
		(property "Reference" "C90"
			(at 0 0 0)
			(layer "B.SilkS")
			(hide yes)
			(effects
				(font
					(size 1.27 1.27)
				)
				(justify mirror)
			)
		)
		(property "Value" ""
			(at 0 0 0)
			(layer "B.Fab")
			(effects
				(font
					(size 1.27 1.27)
				)
				(justify mirror)
			)
		)
		(duplicate_pad_numbers_are_jumpers no)
		(fp_line
			(start -0.7874 -0.4064)
			(end -0.7874 0.4064)
			(stroke
				(width 0.1524)
				(type default)
			)
			(layer "B.SilkS")
		)
		(fp_line
			(start -0.7874 0.4064)
			(end 0.7874 0.4064)
			(stroke
				(width 0.1524)
				(type default)
			)
			(layer "B.SilkS")
		)
		(fp_line
			(start 0.7874 -0.4064)
			(end -0.7874 -0.4064)
			(stroke
				(width 0.1524)
				(type default)
			)
			(layer "B.SilkS")
		)
		(fp_line
			(start 0.7874 0.4064)
			(end 0.7874 -0.4064)
			(stroke
				(width 0.1524)
				(type default)
			)
			(layer "B.SilkS")
		)
		(fp_line
			(start -0.67945 -0.3048)
			(end -0.67945 0.3048)
			(stroke
				(width 0.1)
				(type default)
			)
			(layer "B.Fab")
		)
		(fp_line
			(start -0.67945 0.3048)
			(end -0.120396 0.3048)
			(stroke
				(width 0.1)
				(type default)
			)
			(layer "B.Fab")
		)
		(fp_line
			(start -0.12065 -0.3048)
			(end -0.67945 -0.3048)
			(stroke
				(width 0.1)
				(type default)
			)
			(layer "B.Fab")
		)
		(fp_line
			(start -0.12065 -0.2794)
			(end -0.12065 -0.3048)
			(stroke
				(width 0.1)
				(type default)
			)
			(layer "B.Fab")
		)
		(fp_line
			(start -0.120396 0.2794)
			(end 0.12065 0.2794)
			(stroke
				(width 0.1)
				(type default)
			)
			(layer "B.Fab")
		)
		(fp_line
			(start -0.120396 0.3048)
			(end -0.120396 0.2794)
			(stroke
				(width 0.1)
				(type default)
			)
			(layer "B.Fab")
		)
		(fp_line
			(start 0.12065 -0.305054)
			(end 0.12065 -0.2794)
			(stroke
				(width 0.1)
				(type default)
			)
			(layer "B.Fab")
		)
		(fp_line
			(start 0.12065 -0.2794)
			(end -0.12065 -0.2794)
			(stroke
				(width 0.1)
				(type default)
			)
			(layer "B.Fab")
		)
		(fp_line
			(start 0.12065 0.2794)
			(end 0.12065 0.3048)
			(stroke
				(width 0.1)
				(type default)
			)
			(layer "B.Fab")
		)
		(fp_line
			(start 0.12065 0.3048)
			(end 0.67945 0.3048)
			(stroke
				(width 0.1)
				(type default)
			)
			(layer "B.Fab")
		)
		(fp_line
			(start 0.67945 -0.305054)
			(end 0.12065 -0.305054)
			(stroke
				(width 0.1)
				(type default)
			)
			(layer "B.Fab")
		)
		(fp_line
			(start 0.67945 0.3048)
			(end 0.67945 -0.305054)
			(stroke
				(width 0.1)
				(type default)
			)
			(layer "B.Fab")
		)
		(pad "1" smd circle
			(at 0.40005 0 180)
			(size 0 0)
			(layers "B.Cu" "B.Mask" "B.Paste")
			(net "P3V3_AUX")
		)
		(pad "2" smd circle
			(at -0.40005 0 180)
			(size 0 0)
			(layers "B.Cu" "B.Mask" "B.Paste")
			(net "GND")
		)
	)
	(footprint ""
		(layer "B.Cu")
		(at 108.845604 -294.01008 180)
		(property "Reference" "C328"
			(at 0 0 0)
			(layer "B.SilkS")
			(hide yes)
			(effects
				(font
					(size 1.27 1.27)
				)
				(justify mirror)
			)
		)
		(property "Value" ""
			(at 0 0 0)
			(layer "B.Fab")
			(effects
				(font
					(size 1.27 1.27)
				)
				(justify mirror)
			)
		)
		(duplicate_pad_numbers_are_jumpers no)
		(fp_line
			(start 1.524 0.762)
			(end 1.524 -0.762)
			(stroke
				(width 0.1524)
				(type default)
			)
			(layer "B.SilkS")
		)
		(fp_line
			(start 1.524 -0.762)
			(end -1.524 -0.762)
			(stroke
				(width 0.1524)
				(type default)
			)
			(layer "B.SilkS")
		)
		(fp_line
			(start -1.524 0.762)
			(end 1.524 0.762)
			(stroke
				(width 0.1524)
				(type default)
			)
			(layer "B.SilkS")
		)
		(fp_line
			(start -1.524 -0.762)
			(end -1.524 0.762)
			(stroke
				(width 0.1524)
				(type default)
			)
			(layer "B.SilkS")
		)
		(fp_line
			(start 1.1049 0.724916)
			(end -1.1049 0.724916)
			(stroke
				(width 0.1)
				(type default)
			)
			(layer "B.Fab")
		)
		(fp_line
			(start 1.1049 -0.724916)
			(end 1.1049 0.724916)
			(stroke
				(width 0.1)
				(type default)
			)
			(layer "B.Fab")
		)
		(fp_line
			(start -1.1049 0.724916)
			(end -1.1049 -0.724916)
			(stroke
				(width 0.1)
				(type default)
			)
			(layer "B.Fab")
		)
		(fp_line
			(start -1.1049 -0.724916)
			(end 1.1049 -0.724916)
			(stroke
				(width 0.1)
				(type default)
			)
			(layer "B.Fab")
		)
		(pad "1" smd rect
			(at 0.889 0 180)
			(size 1.016 1.27)
			(layers "B.Cu" "B.Mask" "B.Paste")
			(net "PVCCIN_CPU1")
		)
		(pad "2" smd rect
			(at -0.889 0 180)
			(size 1.016 1.27)
			(layers "B.Cu" "B.Mask" "B.Paste")
			(net "GND")
		)
	)
	(footprint ""
		(layer "B.Cu")
		(at 358.328214 -337.860386)
		(property "Reference" "PR149"
			(at 0 0 0)
			(layer "B.SilkS")
			(hide yes)
			(effects
				(font
					(size 1.27 1.27)
				)
				(justify mirror)
			)
		)
		(property "Value" ""
			(at 0 0 0)
			(layer "B.Fab")
			(effects
				(font
					(size 1.27 1.27)
				)
				(justify mirror)
			)
		)
		(duplicate_pad_numbers_are_jumpers no)
		(fp_line
			(start -0.7874 -0.4064)
			(end -0.7874 0.4064)
			(stroke
				(width 0.1524)
				(type default)
			)
			(layer "B.SilkS")
		)
		(fp_line
			(start -0.7874 0.4064)
			(end 0.7874 0.4064)
			(stroke
				(width 0.1524)
				(type default)
			)
			(layer "B.SilkS")
		)
		(fp_line
			(start 0.7874 -0.4064)
			(end -0.7874 -0.4064)
			(stroke
				(width 0.1524)
				(type default)
			)
			(layer "B.SilkS")
		)
		(fp_line
			(start 0.7874 0.4064)
			(end 0.7874 -0.4064)
			(stroke
				(width 0.1524)
				(type default)
			)
			(layer "B.SilkS")
		)
		(fp_line
			(start -0.67945 -0.3048)
			(end -0.67945 0.3048)
			(stroke
				(width 0.1)
				(type default)
			)
			(layer "B.Fab")
		)
		(fp_line
			(start -0.67945 0.3048)
			(end -0.120396 0.3048)
			(stroke
				(width 0.1)
				(type default)
			)
			(layer "B.Fab")
		)
		(fp_line
			(start -0.12065 -0.3048)
			(end -0.67945 -0.3048)
			(stroke
				(width 0.1)
				(type default)
			)
			(layer "B.Fab")
		)
		(fp_line
			(start -0.12065 -0.2794)
			(end -0.12065 -0.3048)
			(stroke
				(width 0.1)
				(type default)
			)
			(layer "B.Fab")
		)
		(fp_line
			(start -0.120396 0.2794)
			(end 0.12065 0.2794)
			(stroke
				(width 0.1)
				(type default)
			)
			(layer "B.Fab")
		)
		(fp_line
			(start -0.120396 0.3048)
			(end -0.120396 0.2794)
			(stroke
				(width 0.1)
				(type default)
			)
			(layer "B.Fab")
		)
		(fp_line
			(start 0.12065 -0.305054)
			(end 0.12065 -0.2794)
			(stroke
				(width 0.1)
				(type default)
			)
			(layer "B.Fab")
		)
		(fp_line
			(start 0.12065 -0.2794)
			(end -0.12065 -0.2794)
			(stroke
				(width 0.1)
				(type default)
			)
			(layer "B.Fab")
		)
		(fp_line
			(start 0.12065 0.2794)
			(end 0.12065 0.3048)
			(stroke
				(width 0.1)
				(type default)
			)
			(layer "B.Fab")
		)
		(fp_line
			(start 0.12065 0.3048)
			(end 0.67945 0.3048)
			(stroke
				(width 0.1)
				(type default)
			)
			(layer "B.Fab")
		)
		(fp_line
			(start 0.67945 -0.305054)
			(end 0.12065 -0.305054)
			(stroke
				(width 0.1)
				(type default)
			)
			(layer "B.Fab")
		)
		(fp_line
			(start 0.67945 0.3048)
			(end 0.67945 -0.305054)
			(stroke
				(width 0.1)
				(type default)
			)
			(layer "B.Fab")
		)
		(pad "1" smd circle
			(at 0.40005 0 180)
			(size 0 0)
			(layers "B.Cu" "B.Mask" "B.Paste")
			(net "PVCCIN_CPU0_VOS3")
		)
		(pad "2" smd circle
			(at -0.40005 0 180)
			(size 0 0)
			(layers "B.Cu" "B.Mask" "B.Paste")
			(net "PVCCIN_CPU0")
		)
	)
)
